FILE_TYPE = CONNECTIVITY;
{Allegro Design Entry HDL 16.6-p007 (v16-6-112F) 10/10/2012}
"PAGE_NUMBER" = 196;
0"NC";
1"GND\g";
2"GND\g";
3"P3V3_STBY\g";
4"P5V\g";
5"P12V\g";
6"GND\g";
7"GND\g";
8"P3V3_STBY\g";
9"GND\g";
10"P3V3_STBY\g";
11"P3V3_STBY\g";
12"GND\g";
13"GND\g";
14"P3V3_STBY\g";
15"P3V3_STBY\g";
16"P12V_STBY\g";
17"P3V3_STBY\g";
18"GND\g";
19"GND\g";
20"P3V3_STBY\g";
21"GND\g";
22"GND\g";
23"GND\g";
24"P3V3\g";
25"GND\g";
26"P3V3_RTC_STBY\g";
27"PWRGD_DSW_PWROK";
28"A_ADM1085_CEXT";
29"PWRGD_P12V_HSC_DLY";
30"PWRGD_P12V_MAIN";
31"PWRGD_P12V_MAIN_R";
32"PWRGD_P12V_HSC_DLY_R";
33"PWRGD_P5V_R";
34"PWRGD_P5V";
35"PWRGD_P3V3";
36"PWRGD_P3V3_R1";
37"PWRGD_P5V_N";
38"PWRGD_P12V_HSC";
39"VSENSE_P12V_ADM1085";
40"PWRGD_P3V3_STBY";
41"A_P3V_BAT_R"VOLTAGE"+3 V"CDS_PHYS_NET_NAME"P3V_BAT_R";
42"A_PG_P5V";
43"A_PG_P12V_MAIN";
44"P3V_BAT_SOURCE"CDS_PHYS_NET_NAME"P3V_BAT_SOURCE"VOLTAGE"+3 V";
%"CAP_A"
"1","(-2200,4500)","0","dev_discrete","I102";
;
SEC_TYPE"0402V"
ROOM"SB_VRD"
CDS_SEC"1"
BOM_COST"SB"
SEC"1"
CDS_LOCATION"C2U26"
CDS_LIB"dev_discrete"
LOCATION"C2U26"
PART_NUMBER"D97712-004"
VALUE"1.0UF"
PACK_TYPE"0402V"
VOLTAGE"6.3V"
NO_XNET_CONNECTION"1"
TOLERANCE"10%"
MATERIAL"X6S";
"B"
$PN"2"12;
"A"
$PN"1"26;
%"DIODE"
"3","(825,3650)","0","mstr_discrete","I103";
;
CDS_SEC"1"
CDS_LIB"mstr_discrete"
SEC_TYPE"SMLF"
SEC"1"
CDS_LOCATION"CR7E1"
PART_NUMBER"C73510-001"
LOCATION"CR7E1"
MATERIAL"IC"
VALUE"BAT54WS"
PACK_TYPE"SMLF";
"C"
$PN"1"40;
"A"
$PN"2"27;
%"TPS3700"
"1","(-500,2300)","0","mstr_vreg","I104";
;
CDS_LOCATION"U8D8"
CDS_LMAN_SYM_OUTLINE"-250,200,250,-200"
CDS_LIB"mstr_vreg"
PACK_TYPE"SM"
CDS_SEC"1"
$SEC"1"
ROOM"V_SUPER"
PART_NUMBER"H69492-001"
LOCATION"U8D8"
MATERIAL"IC";
"VDD"
$PN"2"3;
"OUTB"
$PN"1"37;
"OUTA"
$PN"6"31;
"INBN"
$PN"3"42;
"INAP"
$PN"4"43;
"GND"
$PN"5"1;
%"CAP_A"
"1","(-1000,1950)","0","dev_discrete","I105";
;
CDS_SEC"1"
$SEC"1"
CDS_LOCATION"C8D4"
ROOM"V_SUPER"
CDS_LIB"dev_discrete"
LOCATION"C8D4"
PART_NUMBER"A36096-030"
VALUE"0.1UF"
TOLERANCE"10%"
VOLTAGE"16V"
MATERIAL"X7R"
PACK_TYPE"0402V";
"B"
$PN"2"2;
"A"
$PN"1"3;
%"RES"
"1","(1350,2400)","0","mstr_discrete","I106";
;
CDS_SEC"1"
CDS_LOCATION"R8D42"
SEC"1"
SEC_TYPE"0402"
ROOM"V_SUPER"
CDS_LIB"mstr_discrete"
PACK_TYPE"0402"
PART_NUMBER"G21796-017"
LOCATION"R8D42"
TOLERANCE"1%"
MATERIAL"CHIP"
VALUE"100.0"
WATTAGE"1/16W";
"B"
$PN"2"30;
"A"
$PN"1"31;
%"GND"
"1","(-150,2000)","0","mstr_symbols","I108";
;
HDL_POWER"GND"
VOLTAGE"0.0V"
SIZE"1B"
CDS_LIB"mstr_symbols"
BODY_TYPE"PLUMBING";
"A\NAC"1;
%"GND"
"1","(-1000,1750)","0","mstr_symbols","I110";
;
HDL_POWER"GND"
SIZE"1B"
CDS_LIB"mstr_symbols"
VOLTAGE"0.0V"
BODY_TYPE"PLUMBING";
"A\NAC"2;
%"P3V3_STBY"
"1","(-1000,2750)","0","mstr_symbols","I111";
;
CDS_LIB"mstr_symbols"
SIZE"1B"
VOLTAGE"3.3V"
BODY_TYPE"PLUMBING"
HDL_POWER"P3V3_STBY";
"G\NAC"3;
%"RES"
"2","(-1750,2800)","0","mstr_discrete","I112";
;
CDS_SEC"1"
CDS_LOCATION"R8D38"
SEC"1"
SEC_TYPE"0402"
ROOM"V_SUPER"
CDS_LIB"mstr_discrete"
PART_NUMBER"G21796-010"
VALUE"100.0K"
LOCATION"R8D38"
TOLERANCE"1%"
WATTAGE"1/16W"
MATERIAL"CHIP"
PACK_TYPE"0402";
"A"
$PN"1"5;
"B"
$PN"2"43;
%"RES"
"2","(-1750,2400)","0","mstr_discrete","I113";
;
CDS_SEC"1"
CDS_LOCATION"R8D40"
SEC"1"
SEC_TYPE"0402"
ROOM"V_SUPER"
CDS_LIB"mstr_discrete"
PART_NUMBER"G21796-059"
LOCATION"R8D40"
WATTAGE"1/16W"
MATERIAL"CHIP"
TOLERANCE"1%"
VALUE"3.74K"
PACK_TYPE"0402";
"A"
$PN"1"43;
"B"
$PN"2"6;
%"RES"
"2","(-1750,1850)","0","mstr_discrete","I114";
;
CDS_SEC"1"
CDS_LOCATION"R8D39"
SEC"1"
SEC_TYPE"0402"
ROOM"V_SUPER"
CDS_LIB"mstr_discrete"
PART_NUMBER"G21796-048"
WATTAGE"1/16W"
TOLERANCE"1%"
VALUE"49.9K"
LOCATION"R8D39"
MATERIAL"CHIP"
PACK_TYPE"0402";
"A"
$PN"1"4;
"B"
$PN"2"42;
%"RES"
"2","(-1750,1450)","0","mstr_discrete","I115";
;
CDS_SEC"1"
CDS_LOCATION"R8D37"
SEC"1"
SEC_TYPE"0402"
ROOM"V_SUPER"
CDS_LIB"mstr_discrete"
PART_NUMBER"G21796-072"
LOCATION"R8D37"
VALUE"4.75K"
WATTAGE"1/16W"
MATERIAL"CHIP"
TOLERANCE"1%"
PACK_TYPE"0402";
"A"
$PN"1"42;
"B"
$PN"2"7;
%"P5V"
"1","(-1750,2050)","0","mstr_symbols","I116";
;
SIZE"1B"
CDS_LIB"mstr_symbols"
VOLTAGE"5.0V"
BODY_TYPE"PLUMBING"
HDL_POWER"P5V";
"G\NAC"4;
%"P12V"
"1","(-1750,3000)","0","mstr_symbols","I117";
;
SIZE"1B"
CDS_LIB"mstr_symbols"
VOLTAGE"12.0V"
BODY_TYPE"PLUMBING"
HDL_POWER"P12V";
"G\NAC"5;
%"GND"
"1","(-1750,2200)","0","mstr_symbols","I118";
;
HDL_POWER"GND"
CDS_LIB"mstr_symbols"
SIZE"1B"
VOLTAGE"0.0V"
BODY_TYPE"PLUMBING";
"A\NAC"6;
%"GND"
"1","(-1750,1250)","0","mstr_symbols","I119";
;
HDL_POWER"GND"
CDS_LIB"mstr_symbols"
SIZE"1B"
VOLTAGE"0.0V"
BODY_TYPE"PLUMBING";
"A\NAC"7;
%"RES"
"2","(50,2650)","0","mstr_discrete","I120";
;
CDS_SEC"1"
CDS_LOCATION"R8D41"
SEC"1"
SEC_TYPE"0402"
ROOM"V_SUPER"
CDS_LIB"mstr_discrete"
WATTAGE"1/16W"
MATERIAL"CHIP"
TOLERANCE"1%"
VALUE"10.0K"
LOCATION"R8D41"
PART_NUMBER"G21796-016"
PACK_TYPE"0402";
"A"
$PN"1"8;
"B"
$PN"2"31;
%"RES"
"2","(250,2000)","0","mstr_discrete","I121";
;
CDS_SEC"1"
CDS_LOCATION"R2P18"
SEC"1"
SEC_TYPE"0402"
ROOM"V_SUPER"
CDS_LIB"mstr_discrete"
LOCATION"R2P18"
VALUE"10.0K"
TOLERANCE"1%"
PART_NUMBER"G21796-016"
PACK_TYPE"0402"
MATERIAL"CHIP"
WATTAGE"1/16W";
"A"
$PN"1"10;
"B"
$PN"2"37;
%"RES"
"2","(750,2200)","0","mstr_discrete","I122";
;
CDS_SEC"1"
CDS_LOCATION"R2P21"
SEC_TYPE"0402"
SEC"1"
ROOM"V_SUPER"
CDS_LIB"mstr_discrete"
PART_NUMBER"G21796-016"
VALUE"10.0K"
LOCATION"R2P21"
TOLERANCE"1%"
MATERIAL"CHIP"
WATTAGE"1/16W"
PACK_TYPE"0402";
"A"
$PN"1"11;
"B"
$PN"2"33;
%"P3V3_STBY"
"1","(50,2850)","0","mstr_symbols","I123";
;
CDS_LIB"mstr_symbols"
SIZE"1B"
VOLTAGE"3.3V"
BODY_TYPE"PLUMBING"
HDL_POWER"P3V3_STBY";
"G\NAC"8;
%"FET_N"
"8","(750,1750)","0","mstr_discrete","I124";
;
CDS_LOCATION"Q2P2"
CDS_SEC"1"
ROOM"V_SUPER"
$SEC"1"
PACK_TYPE"SOT23"
CDS_LIB"mstr_discrete"
LOCATION"Q2P2"
PART_NUMBER"C79254-001"
VALUE"2N7002"
MATERIAL"FET";
"GATE"
$PN"1"37;
"DRN"
$PN"3"33;
"SRC"
$PN"2"9;
%"GND"
"1","(750,1450)","0","mstr_symbols","I125";
;
HDL_POWER"GND"
VOLTAGE"0.0V"
CDS_LIB"mstr_symbols"
SIZE"1B"
BODY_TYPE"PLUMBING";
"A\NAC"9;
%"P3V3_STBY"
"1","(250,2300)","0","mstr_symbols","I126";
;
SIZE"1B"
CDS_LIB"mstr_symbols"
VOLTAGE"3.3V"
BODY_TYPE"PLUMBING"
HDL_POWER"P3V3_STBY";
"G\NAC"10;
%"P3V3_STBY"
"1","(750,2600)","0","mstr_symbols","I127";
;
SIZE"1B"
CDS_LIB"mstr_symbols"
VOLTAGE"3.3V"
BODY_TYPE"PLUMBING"
HDL_POWER"P3V3_STBY";
"G\NAC"11;
%"DIODE"
"3","(1050,3400)","0","mstr_discrete","I128";
;
CDS_SEC"1"
CDS_LOCATION"CR8E1"
SEC"1"
SEC_TYPE"SMLF"
CDS_LIB"mstr_discrete"
PART_NUMBER"C73510-001"
MATERIAL"IC"
PACK_TYPE"SMLF"
VALUE"BAT54WS"
LOCATION"CR8E1";
"C"
$PN"1"38;
"A"
$PN"2"29;
%"GND"
"1","(-2200,4250)","0","mstr_symbols","I43";
;
HDL_POWER"GND"
VOLTAGE"0"
SIZE"1B"
CDS_LIB"mstr_symbols"
BODY_TYPE"PLUMBING"
ROOM"BATTERY_CIRCUIT";
"A\NAC"12;
%"RES"
"1","(-3650,4550)","0","mstr_discrete","I46";
;
CDS_SEC"1"
ROOM"SB_VRD"
SEC"1"
SEC_TYPE"0402"
BOM_COST"SB"
CDS_LOCATION"R2U43"
CDS_LIB"mstr_discrete"
PACK_TYPE"0402"
LOCATION"R2U43"
PART_NUMBER"G21796-026"
MATERIAL"CHIP"
VALUE"1.00K"
TOLERANCE"1%"
WATTAGE"1/16W";
"B"
$PN"2"41;
"A"
$PN"1"44;
%"BATTERY"
"1","(-4375,4200)","0","mstr_misc","I47";
;
ROOM"SB_VRD"
PACK_TYPE"PLCLF"
CDS_LOCATION"BT8G1"
CDS_LIB"mstr_misc"
BOM_COST"SB"
LOCATION"BT8G1"
PART_NUMBER"202168-001";
%"VERT_BATT_3PIN"
"1","(-4800,4550)","0","mstr_discrete","I51";
;
CDS_SEC"1"
PACK_TYPE"PIP"
CDS_LOCATION"XBT8G1"
SEC"1"
SEC_TYPE"PIP"
ROOM"SB_VRD"
CDS_LIB"mstr_discrete"
LOCATION"XBT8G1"
MATERIAL"3PVERT"
PART_NUMBER"C68619-005";
"P1\NAC"
$PN"1"44;
"P2\NAC"
$PN"2"44;
"N\NAC"
$PN"3"13;
%"GND"
"1","(-5050,4250)","0","mstr_symbols","I52";
;
HDL_POWER"GND"
CDS_LIB"mstr_symbols"
VOLTAGE"0"
SIZE"1B"
BODY_TYPE"PLUMBING"
ROOM"SB";
"A\NAC"13;
%"DIODE2A_DUAL"
"1","(-2700,4650)","0","mstr_discrete","I53";
;
CDS_SEC"1"
CDS_LIB"mstr_discrete"
ROOM"SB_VRD"
CDS_LOCATION"CR2U1"
SEC"1"
SEC_TYPE"SMLF"
PART_NUMBER"C90169-001"
VALUE"BAS70-05"
PACK_TYPE"SMLF"
MATERIAL"DIO"
LOCATION"CR2U1";
"C"
$PN"3"26;
"A1"
$PN"1"14;
"A2"
$PN"2"41;
%"P3V3_STBY"
"1","(-3250,4975)","0","mstr_symbols","I54";
;
HDL_POWER"P3V3_STBY"
BODY_TYPE"PLUMBING"
CDS_LIB"mstr_symbols"
SIZE"1B"
VOLTAGE"3.3V";
"G\NAC"14;
%"P3V3_STBY"
"1","(-25,5000)","0","mstr_symbols","I56";
;
SIZE"1B"
VOLTAGE"3.3V"
CDS_LIB"mstr_symbols"
BODY_TYPE"PLUMBING"
HDL_POWER"P3V3_STBY";
"G\NAC"15;
%"P12V_STBY"
"1","(-525,5000)","0","mstr_symbols","I57";
;
SIZE"1B"
VOLTAGE"12.0V"
CDS_LIB"mstr_symbols"
BODY_TYPE"PLUMBING"
HDL_POWER"P12V_STBY";
"G\NAC"16;
%"P3V3_STBY"
"1","(1325,4900)","0","mstr_symbols","I58";
;
CDS_LIB"mstr_symbols"
SIZE"1B"
VOLTAGE"3.3V"
BODY_TYPE"PLUMBING"
HDL_POWER"P3V3_STBY";
"G\NAC"17;
%"RES"
"2","(1325,4650)","0","mstr_discrete","I59";
;
CDS_SEC"1"
SEC"1"
SEC_TYPE"0402"
ROOM"V_SUPER"
CDS_LOCATION"R3P44"
CDS_LIB"mstr_discrete"
PART_NUMBER"G21796-072"
WATTAGE"1/16W"
VALUE"4.75K"
TOLERANCE"1%"
LOCATION"R3P44"
MATERIAL"CHIP"
PACK_TYPE"0402";
"A"
$PN"1"17;
"B"
$PN"2"27;
%"CAP"
"1","(1225,4050)","0","mstr_discrete","I60";
;
CDS_SEC"1"
CDS_LOCATION"C3P45"
SEC"1"
SEC_TYPE"0402"
ROOM"V_SUPER"
CDS_LIB"mstr_discrete"
LOCATION"C3P45"
VALUE"0.047UF"
PART_NUMBER"A36096-090"
TOLERANCE"10%"
PACK_TYPE"0402"
VOLTAGE"25V"
MATERIAL"X7R";
"A"
$PN"1"28;
"B"
$PN"2"19;
%"GND"
"1","(1125,4100)","0","mstr_symbols","I61";
;
HDL_POWER"GND"
CDS_LIB"mstr_symbols"
SIZE"1B"
BODY_TYPE"PLUMBING"
VOLTAGE"0.0V";
"A\NAC"18;
%"GND"
"1","(1225,3850)","0","mstr_symbols","I62";
;
SIZE"1B"
HDL_POWER"GND"
CDS_LIB"mstr_symbols"
BODY_TYPE"PLUMBING"
VOLTAGE"0.0V";
"A\NAC"19;
%"RES"
"1","(1350,2000)","0","mstr_discrete","I65";
;
CDS_SEC"1"
CDS_LOCATION"R2P20"
SEC"1"
SEC_TYPE"0402"
ROOM"V_SUPER"
CDS_LIB"mstr_discrete"
PART_NUMBER"G21796-017"
LOCATION"R2P20"
PACK_TYPE"0402"
MATERIAL"CHIP"
TOLERANCE"1%"
VALUE"100.0"
WATTAGE"1/16W";
"B"
$PN"2"34;
"A"
$PN"1"33;
%"RES"
"1","(1300,1250)","0","mstr_discrete","I68";
;
CDS_SEC"1"
CDS_LIB"mstr_discrete"
SEC_TYPE"0402"
SEC"1"
CDS_LOCATION"R1L16"
ROOM"V_SUPER"
PACK_TYPE"0402"
PART_NUMBER"G21796-047"
MATERIAL"CHIP"
TOLERANCE"1%"
LOCATION"R1L16"
VALUE"49.9"
WATTAGE"1/16W";
"B"
$PN"2"35;
"A"
$PN"1"36;
%"P3V3_STBY"
"1","(275,4900)","0","mstr_symbols","I69";
;
SIZE"1B"
CDS_LIB"mstr_symbols"
VOLTAGE"3.3V"
BODY_TYPE"PLUMBING"
HDL_POWER"P3V3_STBY";
"G\NAC"20;
%"ADM1085"
"1","(725,4400)","0","mstr_analog","I70";
;
CDS_SEC"1"
CDS_LIB"mstr_analog"
PACK_TYPE"SMT"
SEC_TYPE"SMT"
SEC"1"
CDS_LOCATION"U7D3"
ROOM"V_SUPER"
LOCATION"U7D3"
PART_NUMBER"H46130-001"
MATERIAL"IC";
"VIN"
$PN"3"39;
"VCC"
$PN"6"20;
"CEXT"
$PN"5"28;
"GND"
$PN"2"18;
"ENOUT"
$PN"4"27;
"ENIN"
$PN"1"40;
%"RES"
"2","(-25,4750)","0","mstr_discrete","I71";
;
CDS_SEC"1"
CDS_LOCATION"R3P50"
SEC"1"
SEC_TYPE"0402"
ROOM"V_SUPER"
CDS_LIB"mstr_discrete"
PART_NUMBER"G21796-016"
LOCATION"R3P50"
MATERIAL"EMPTY"
VALUE"10.0K"
WATTAGE"1/16W"
TOLERANCE"1%"
PACK_TYPE"0402";
"A"
$PN"1"15;
"B"
$PN"2"40;
%"CAP_A"
"1","(275,3950)","0","dev_discrete","I72";
;
CDS_SEC"1"
SEC"1"
SEC_TYPE"0402V"
ROOM"V_SUPER"
CDS_LOCATION"C3P46"
CDS_LIB"dev_discrete"
PART_NUMBER"A36096-030"
LOCATION"C3P46"
VALUE"0.1UF"
TOLERANCE"10%"
VOLTAGE"16V"
MATERIAL"X7R"
PACK_TYPE"0402V";
"B"
$PN"2"21;
"A"
$PN"1"20;
%"GND"
"1","(275,3750)","0","mstr_symbols","I73";
;
HDL_POWER"GND"
SIZE"1B"
CDS_LIB"mstr_symbols"
BODY_TYPE"PLUMBING"
VOLTAGE"0.0V";
"A\NAC"21;
%"RES"
"2","(-525,4750)","0","mstr_discrete","I74";
;
CDS_SEC"1"
CDS_LOCATION"R3P48"
SEC"1"
SEC_TYPE"0402"
ROOM"V_SUPER"
CDS_LIB"mstr_discrete"
PART_NUMBER"G21796-058"
LOCATION"R3P48"
VALUE"90.9K"
TOLERANCE"1%"
MATERIAL"CHIP"
WATTAGE"1/16W"
PACK_TYPE"0402";
"A"
$PN"1"16;
"B"
$PN"2"39;
%"RES"
"2","(-525,4250)","0","mstr_discrete","I75";
;
CDS_SEC"1"
ROOM"V_SUPER"
SEC_TYPE"0402"
SEC"1"
CDS_LOCATION"R3P51"
CDS_LIB"mstr_discrete"
PART_NUMBER"G21796-146"
WATTAGE"1/16W"
MATERIAL"CHIP"
TOLERANCE"1%"
VALUE"6.34K"
LOCATION"R3P51"
PACK_TYPE"0402";
"A"
$PN"1"39;
"B"
$PN"2"22;
%"GND"
"1","(-525,4050)","0","mstr_symbols","I76";
;
HDL_POWER"GND"
SIZE"1B"
VOLTAGE"0.0V"
CDS_LIB"mstr_symbols"
BODY_TYPE"PLUMBING";
"A\NAC"22;
%"ADM809"
"1","(200,1350)","0","mstr_analog","I80";
;
ROOM"V_SUPER"
CDS_SEC"1"
PACK_TYPE"SMLF"
$SEC"1"
CDS_LOCATION"U1L3"
CDS_LIB"mstr_analog"
MATERIAL"IC"
LOCATION"U1L3"
PART_NUMBER"D23047-001"
POWER_GROUP"GND=GND;";
"RESET_N \B"
$PN"2"36;
"VCC"
$PN"3"24;
%"CAP_A"
"1","(-300,1250)","0","dev_discrete","I81";
;
CDS_SEC"1"
$SEC"1"
CDS_LOCATION"C1L16"
ROOM"V_SUPER"
CDS_LIB"dev_discrete"
PART_NUMBER"A36096-030"
LOCATION"C1L16"
VALUE"0.1UF"
TOLERANCE"10%"
PACK_TYPE"0402V"
VOLTAGE"16V"
MATERIAL"X7R";
"B"
$PN"2"23;
"A"
$PN"1"24;
%"GND"
"1","(-300,1050)","0","mstr_symbols","I82";
;
HDL_POWER"GND"
CDS_LIB"mstr_symbols"
SIZE"1B"
VOLTAGE"0.0V"
BODY_TYPE"PLUMBING";
"A\NAC"23;
%"P3V3"
"1","(-300,1500)","0","mstr_symbols","I83";
;
SIZE"1B"
CDS_LIB"mstr_symbols"
VOLTAGE"3.3V"
BODY_TYPE"PLUMBING"
HDL_POWER"P3V3";
"G\NAC"24;
%"ADM809"
"1","(400,3100)","0","mstr_analog","I89";
;
PACK_TYPE"SMLF"
CDS_LIB"mstr_analog"
CDS_SEC"1"
$SEC"1"
CDS_LOCATION"U8E2"
ROOM"V_SUPER"
LOCATION"U8E2"
MATERIAL"IC"
PART_NUMBER"D23047-001"
POWER_GROUP"GND=GND;";
"RESET_N \B"
$PN"2"32;
"VCC"
$PN"3"38;
%"RES"
"1","(1200,3000)","0","mstr_discrete","I90";
;
CDS_SEC"1"
ROOM"V_SUPER"
SEC_TYPE"0402"
SEC"1"
CDS_LOCATION"R8E7"
CDS_LIB"mstr_discrete"
PART_NUMBER"G21796-250"
LOCATION"R8E7"
PACK_TYPE"0402"
TOLERANCE"1.0%"
MATERIAL"CHIP"
VALUE"22.1"
WATTAGE"1/16W";
"B"
$PN"2"29;
"A"
$PN"1"32;
%"CAP_A"
"1","(-300,2950)","0","dev_discrete","I94";
;
CDS_SEC"1"
SEC"1"
SEC_TYPE"0402V"
ROOM"V_SUPER"
CDS_LOCATION"C8E3"
CDS_LIB"dev_discrete"
PART_NUMBER"A36096-030"
LOCATION"C8E3"
VALUE"0.1UF"
TOLERANCE"10%"
PACK_TYPE"0402V"
VOLTAGE"16V"
MATERIAL"X7R";
"B"
$PN"2"25;
"A"
$PN"1"38;
%"GND"
"1","(-300,2750)","0","mstr_symbols","I95";
;
SIZE"1B"
HDL_POWER"GND"
CDS_LIB"mstr_symbols"
VOLTAGE"0.0V"
BODY_TYPE"PLUMBING";
"A\NAC"25;
%"P3V3_RTC_STBY"
"1","(-2200,4875)","0","mstr_symbols","I97";
;
CDS_LIB"mstr_symbols"
BOM_COST"SB"
ROOM"SB_DECOUPLING"
HDL_POWER"P3V3_RTC_STBY"
BODY_TYPE"PLUMBING"
VOLTAGE"3.3V";
"G\NAC"26;
END.
